FILE_TYPE = MACRO_DRAWING;
SET COLOR_WIRE YELLOW;
SET COLOR_PROP ORANGE;
SET COLOR_DOT WHITE;
SET COLOR_ARC YELLOW;
SET COLOR_BODY GREEN;
SET COLOR_NOTE PURPLE;
SET PROP_DISPLAY VALUE;
SET PAGE_NUMBER P220;
FORCEADD OFFPAGE..1
(-900 3625);
FORCEPROP 2 LAST $XR0 231 
J 0
(-1152 3625);
DISPLAY 0.638298 (-1152 3625);
PAINT MONO (-1152 3625);
FORCEPROP 2 LAST PATH I1
J 0
(-1175 3675);
DISPLAY 1.021277 (-1175 3675);
DISPLAY INVISIBLE (-1175 3675);
FORCEPROP 1 LAST COMMENT_BODY TRUE
J 0
(-775 3525);
DISPLAY 0.872340 (-775 3525);
PAINT GREEN (-775 3525);
DISPLAY INVISIBLE (-775 3525);
FORCEPROP 1 LAST OFFPAGE TRUE
J 0
(-575 3500);
DISPLAY 0.872340 (-575 3500);
PAINT GREEN (-575 3500);
DISPLAY INVISIBLE (-575 3500);
FORCEPROP 2 LAST CDS_LIB standard
J 0
(-900 3625);
PAINT MONO (-900 3625);
DISPLAY INVISIBLE (-900 3625);
FORCEADD Q_RES..1
(825 3225);
FORCEPROP 1 LAST PART_NUMBER CS03322FB03
J 0
(700 3275);
DISPLAY 0.638298 (700 3275);
DISPLAY INVISIBLE (700 3275);
FORCEPROP 1 LAST TOLERANCE 1%
J 0
(1050 3225);
DISPLAY 0.510638 (1050 3225);
FORCEPROP 1 LAST MATERIAL CHIP
J 0
(1125 3225);
DISPLAY 0.510638 (1125 3225);
FORCEPROP 1 LAST VALUE 33.2
J 2
(1025 3225);
DISPLAY 0.510638 (1025 3225);
FORCEPROP 1 LAST $LOCATION R3589
J 0
(575 3225);
DISPLAY 0.787234 (575 3225);
FORCEPROP 1 LASTPIN (725 3225) $PN 1
J 0
(737 3237);
DISPLAY 0.787234 (737 3237);
FORCEPROP 1 LASTPIN (925 3225) $PN 2
J 0
(887 3237);
DISPLAY 0.787234 (887 3237);
FORCEPROP 2 LAST CDS_LIB pure_quanta
J 0
(825 3225);
PAINT MONO (825 3225);
DISPLAY INVISIBLE (825 3225);
FORCEPROP 1 LAST PATH I11
J 0
(775 3375);
DISPLAY 0.978723 (775 3375);
PAINT WHITE (775 3375);
DISPLAY INVISIBLE (775 3375);
FORCEPROP 1 LAST PACK_TYPE 0402LF
J 0
(1175 3225);
DISPLAY 0.638298 (1175 3225);
DISPLAY INVISIBLE (1175 3225);
FORCEPROP 1 LAST WATTAGE 1/16W
J 2
(1025 3325);
DISPLAY 0.638298 (1025 3325);
DISPLAY INVISIBLE (1025 3325);
FORCEPROP 2 LAST CDS_LOCATION R3589
J 0
(775 3425);
DISPLAY 1.021277 (775 3425);
DISPLAY INVISIBLE (775 3425);
FORCEPROP 2 LAST $SEC 1
J 0
(775 3425);
DISPLAY 0.680851 (775 3425);
PAINT MONO (775 3425);
DISPLAY INVISIBLE (775 3425);
FORCEPROP 2 LAST CDS_SEC 1
J 0
(775 3425);
DISPLAY 1.021277 (775 3425);
DISPLAY INVISIBLE (775 3425);
FORCEADD OFFPAGE..3
(2500 3225);
FORCEPROP 2 LAST $XR0 171 
J 0
(2714 3225);
DISPLAY 0.638298 (2714 3225);
PAINT MONO (2714 3225);
FORCEPROP 2 LAST PATH I12
J 0
(2975 3275);
DISPLAY 1.021277 (2975 3275);
DISPLAY INVISIBLE (2975 3275);
FORCEPROP 2 LAST CDS_LIB standard
J 0
(2500 3225);
PAINT MONO (2500 3225);
DISPLAY INVISIBLE (2500 3225);
FORCEPROP 1 LAST COMMENT_BODY TRUE
J 0
(2450 3125);
DISPLAY 0.872340 (2450 3125);
PAINT GREEN (2450 3125);
DISPLAY INVISIBLE (2450 3125);
FORCEPROP 1 LAST OFFPAGE TRUE
J 0
(2825 3100);
DISPLAY 0.872340 (2825 3100);
DISPLAY INVISIBLE (2825 3100);
FORCEADD OFFPAGE..2
(2500 3275);
FORCEPROP 2 LAST $XR0 171 
J 0
(2689 3275);
DISPLAY 0.638298 (2689 3275);
PAINT MONO (2689 3275);
FORCEPROP 2 LAST PATH I13
J 0
(2950 3325);
DISPLAY 1.021277 (2950 3325);
DISPLAY INVISIBLE (2950 3325);
FORCEPROP 1 LAST COMMENT_BODY TRUE
J 0
(2455 3180);
DISPLAY 1.170213 (2455 3180);
PAINT GREEN (2455 3180);
DISPLAY INVISIBLE (2455 3180);
FORCEPROP 1 LAST OFFPAGE TRUE
J 0
(2825 3150);
DISPLAY 1.170213 (2825 3150);
PAINT GREEN (2825 3150);
DISPLAY INVISIBLE (2825 3150);
FORCEPROP 2 LAST CDS_LIB standard
J 0
(2500 3275);
PAINT MONO (2500 3275);
DISPLAY INVISIBLE (2500 3275);
FORCEADD OFFPAGE..3
(2500 2950);
FORCEPROP 2 LAST $XR0 172 
J 0
(2714 2950);
DISPLAY 0.638298 (2714 2950);
PAINT MONO (2714 2950);
FORCEPROP 2 LAST CDS_LIB standard
J 0
(2500 2950);
PAINT MONO (2500 2950);
DISPLAY INVISIBLE (2500 2950);
FORCEPROP 1 LAST COMMENT_BODY TRUE
J 0
(2450 2850);
DISPLAY 0.872340 (2450 2850);
PAINT GREEN (2450 2850);
DISPLAY INVISIBLE (2450 2850);
FORCEPROP 1 LAST OFFPAGE TRUE
J 0
(2825 2825);
DISPLAY 0.872340 (2825 2825);
DISPLAY INVISIBLE (2825 2825);
FORCEPROP 2 LAST PATH I14
J 0
(2850 3000);
DISPLAY 1.021277 (2850 3000);
DISPLAY INVISIBLE (2850 3000);
FORCEADD OFFPAGE..2
(2500 3000);
FORCEPROP 2 LAST $XR0 172 
J 0
(2689 3000);
DISPLAY 0.638298 (2689 3000);
PAINT MONO (2689 3000);
FORCEPROP 1 LAST COMMENT_BODY TRUE
J 0
(2455 2905);
DISPLAY 1.170213 (2455 2905);
PAINT GREEN (2455 2905);
DISPLAY INVISIBLE (2455 2905);
FORCEPROP 1 LAST OFFPAGE TRUE
J 0
(2825 2875);
DISPLAY 1.170213 (2825 2875);
PAINT GREEN (2825 2875);
DISPLAY INVISIBLE (2825 2875);
FORCEPROP 2 LAST CDS_LIB standard
J 0
(2500 3000);
PAINT MONO (2500 3000);
DISPLAY INVISIBLE (2500 3000);
FORCEPROP 2 LAST PATH I15
J 0
(2825 3050);
DISPLAY 1.021277 (2825 3050);
DISPLAY INVISIBLE (2825 3050);
FORCEADD Q_RES..1
(825 3275);
FORCEPROP 1 LAST PART_NUMBER CS03322FB03
J 0
(700 3350);
DISPLAY 0.510638 (700 3350);
DISPLAY INVISIBLE (700 3350);
FORCEPROP 1 LAST PACK_TYPE 0402LF
J 0
(700 3400);
DISPLAY 0.510638 (700 3400);
FORCEPROP 1 LAST WATTAGE 1/16W
J 2
(1000 3400);
DISPLAY 0.510638 (1000 3400);
FORCEPROP 1 LAST MATERIAL CHIP
J 0
(1125 3275);
DISPLAY 0.510638 (1125 3275);
FORCEPROP 1 LAST TOLERANCE 1%
J 0
(1050 3275);
DISPLAY 0.510638 (1050 3275);
FORCEPROP 1 LAST VALUE 33.2
J 2
(1025 3275);
DISPLAY 0.510638 (1025 3275);
FORCEPROP 1 LAST $LOCATION R3588
J 0
(575 3275);
DISPLAY 0.787234 (575 3275);
FORCEPROP 1 LASTPIN (725 3275) $PN 1
J 0
(737 3287);
DISPLAY 0.787234 (737 3287);
FORCEPROP 1 LASTPIN (925 3275) $PN 2
J 0
(887 3287);
DISPLAY 0.787234 (887 3287);
FORCEPROP 2 LAST CDS_LIB pure_quanta
J 0
(825 3275);
PAINT MONO (825 3275);
DISPLAY INVISIBLE (825 3275);
FORCEPROP 1 LAST PATH I16
J 0
(775 3425);
DISPLAY 0.978723 (775 3425);
PAINT WHITE (775 3425);
DISPLAY INVISIBLE (775 3425);
FORCEPROP 2 LAST CDS_LOCATION R3588
J 0
(775 3475);
DISPLAY 1.021277 (775 3475);
DISPLAY INVISIBLE (775 3475);
FORCEPROP 2 LAST $SEC 1
J 0
(775 3475);
DISPLAY 0.680851 (775 3475);
PAINT MONO (775 3475);
DISPLAY INVISIBLE (775 3475);
FORCEPROP 2 LAST CDS_SEC 1
J 0
(775 3475);
DISPLAY 1.021277 (775 3475);
DISPLAY INVISIBLE (775 3475);
FORCEADD Q_RES..1
(825 3000);
FORCEPROP 1 LAST PART_NUMBER CS03322FB03
J 0
(700 3075);
DISPLAY 0.510638 (700 3075);
DISPLAY INVISIBLE (700 3075);
FORCEPROP 1 LAST VALUE 33.2
J 2
(1025 3000);
DISPLAY 0.510638 (1025 3000);
FORCEPROP 1 LAST MATERIAL CHIP
J 0
(1125 3000);
DISPLAY 0.510638 (1125 3000);
FORCEPROP 1 LAST TOLERANCE 1%
J 0
(1050 3000);
DISPLAY 0.510638 (1050 3000);
FORCEPROP 1 LAST WATTAGE 1/16W
J 2
(1000 3125);
DISPLAY 0.510638 (1000 3125);
FORCEPROP 1 LAST PACK_TYPE 0402LF
J 0
(700 3125);
DISPLAY 0.510638 (700 3125);
FORCEPROP 1 LAST $LOCATION R3590
J 0
(575 3000);
DISPLAY 0.808511 (575 3000);
FORCEPROP 1 LASTPIN (725 3000) $PN 1
J 0
(737 3012);
DISPLAY 0.787234 (737 3012);
FORCEPROP 1 LASTPIN (925 3000) $PN 2
J 0
(887 3012);
DISPLAY 0.787234 (887 3012);
FORCEPROP 2 LAST CDS_LIB pure_quanta
J 0
(825 3000);
DISPLAY INVISIBLE (825 3000);
FORCEPROP 1 LAST PATH I17
J 0
(775 3150);
DISPLAY 0.978723 (775 3150);
PAINT WHITE (775 3150);
DISPLAY INVISIBLE (775 3150);
FORCEPROP 0 LAST CDS_LOCATION R3590
J 0
(1000 3150);
DISPLAY 1.021277 (1000 3150);
DISPLAY INVISIBLE (1000 3150);
FORCEPROP 0 LAST $SEC 1
J 0
(1000 3150);
DISPLAY 0.680851 (1000 3150);
PAINT MONO (1000 3150);
DISPLAY INVISIBLE (1000 3150);
FORCEPROP 0 LAST CDS_SEC 1
J 0
(1000 3150);
DISPLAY 1.021277 (1000 3150);
DISPLAY INVISIBLE (1000 3150);
FORCEADD Q_RES..1
(825 2950);
FORCEPROP 1 LAST PART_NUMBER CS03322FB03
J 0
(700 3000);
DISPLAY 0.638298 (700 3000);
DISPLAY INVISIBLE (700 3000);
FORCEPROP 1 LAST TOLERANCE 1%
J 0
(1050 2950);
DISPLAY 0.510638 (1050 2950);
FORCEPROP 1 LAST MATERIAL CHIP
J 0
(1125 2950);
DISPLAY 0.510638 (1125 2950);
FORCEPROP 1 LAST VALUE 33.2
J 2
(1025 2950);
DISPLAY 0.510638 (1025 2950);
FORCEPROP 1 LAST $LOCATION R3591
J 0
(575 2950);
DISPLAY 0.808511 (575 2950);
FORCEPROP 1 LASTPIN (725 2950) $PN 1
J 0
(737 2962);
DISPLAY 0.787234 (737 2962);
FORCEPROP 1 LASTPIN (925 2950) $PN 2
J 0
(887 2962);
DISPLAY 0.787234 (887 2962);
FORCEPROP 2 LAST CDS_LIB pure_quanta
J 0
(825 2950);
DISPLAY INVISIBLE (825 2950);
FORCEPROP 1 LAST WATTAGE 1/16W
J 2
(1025 3050);
DISPLAY 0.638298 (1025 3050);
DISPLAY INVISIBLE (1025 3050);
FORCEPROP 1 LAST PACK_TYPE 0402LF
J 0
(1175 2950);
DISPLAY 0.638298 (1175 2950);
DISPLAY INVISIBLE (1175 2950);
FORCEPROP 1 LAST PATH I18
J 0
(775 3100);
DISPLAY 0.978723 (775 3100);
PAINT WHITE (775 3100);
DISPLAY INVISIBLE (775 3100);
FORCEPROP 0 LAST CDS_LOCATION R3591
J 0
(575 3000);
DISPLAY 1.021277 (575 3000);
DISPLAY INVISIBLE (575 3000);
FORCEPROP 0 LAST $SEC 1
J 0
(575 3000);
DISPLAY 0.680851 (575 3000);
PAINT MONO (575 3000);
DISPLAY INVISIBLE (575 3000);
FORCEPROP 0 LAST CDS_SEC 1
J 0
(575 3000);
DISPLAY 1.021277 (575 3000);
DISPLAY INVISIBLE (575 3000);
FORCEADD Q_RES..1
(825 2375);
FORCEPROP 1 LAST PART_NUMBER CS03322FB03
J 0
(700 2425);
DISPLAY 0.638298 (700 2425);
DISPLAY INVISIBLE (700 2425);
FORCEPROP 1 LAST MATERIAL CHIP
J 0
(1125 2375);
DISPLAY 0.510638 (1125 2375);
FORCEPROP 1 LAST TOLERANCE 1%
J 0
(1050 2375);
DISPLAY 0.510638 (1050 2375);
FORCEPROP 1 LAST VALUE 33.2
J 2
(1025 2375);
DISPLAY 0.510638 (1025 2375);
FORCEPROP 1 LAST $LOCATION R3593
J 0
(575 2375);
DISPLAY 0.808511 (575 2375);
FORCEPROP 1 LASTPIN (725 2375) $PN 1
J 0
(737 2387);
DISPLAY 0.787234 (737 2387);
FORCEPROP 1 LASTPIN (925 2375) $PN 2
J 0
(887 2387);
DISPLAY 0.787234 (887 2387);
FORCEPROP 2 LAST CDS_LIB pure_quanta
J 0
(825 2375);
DISPLAY INVISIBLE (825 2375);
FORCEPROP 1 LAST WATTAGE 1/16W
J 2
(1025 2475);
DISPLAY 0.638298 (1025 2475);
DISPLAY INVISIBLE (1025 2475);
FORCEPROP 1 LAST PACK_TYPE 0402LF
J 0
(1175 2375);
DISPLAY 0.638298 (1175 2375);
DISPLAY INVISIBLE (1175 2375);
FORCEPROP 1 LAST PATH I19
J 0
(775 2525);
DISPLAY 0.978723 (775 2525);
PAINT WHITE (775 2525);
DISPLAY INVISIBLE (775 2525);
FORCEPROP 0 LAST CDS_LOCATION R3593
J 0
(575 2425);
DISPLAY 1.021277 (575 2425);
DISPLAY INVISIBLE (575 2425);
FORCEPROP 0 LAST $SEC 1
J 0
(575 2425);
DISPLAY 0.680851 (575 2425);
PAINT MONO (575 2425);
DISPLAY INVISIBLE (575 2425);
FORCEPROP 0 LAST CDS_SEC 1
J 0
(575 2425);
DISPLAY 1.021277 (575 2425);
DISPLAY INVISIBLE (575 2425);
FORCEADD OFFPAGE..3
R 2
(-900 3575);
FORCEPROP 2 LAST $XR0 231 
J 0
(-1180 3575);
DISPLAY 0.638298 (-1180 3575);
PAINT MONO (-1180 3575);
FORCEPROP 2 LAST PATH I2
J 0
(-1175 3625);
DISPLAY 1.021277 (-1175 3625);
DISPLAY INVISIBLE (-1175 3625);
FORCEPROP 1 LAST OFFPAGE TRUE
J 2
(-1225 3450);
DISPLAY 0.872340 (-1225 3450);
DISPLAY INVISIBLE (-1225 3450);
FORCEPROP 1 LAST COMMENT_BODY TRUE
J 2
(-850 3475);
DISPLAY 0.872340 (-850 3475);
PAINT GREEN (-850 3475);
DISPLAY INVISIBLE (-850 3475);
FORCEPROP 2 LAST CDS_LIB standard
J 0
(-900 3575);
PAINT MONO (-900 3575);
DISPLAY INVISIBLE (-900 3575);
FORCEADD Q_RES..1
(825 2425);
FORCEPROP 1 LAST PART_NUMBER CS03322FB03
J 0
(700 2500);
DISPLAY 0.510638 (700 2500);
DISPLAY INVISIBLE (700 2500);
FORCEPROP 1 LAST VALUE 33.2
J 2
(1025 2425);
DISPLAY 0.510638 (1025 2425);
FORCEPROP 1 LAST PACK_TYPE 0402LF
J 0
(700 2550);
DISPLAY 0.510638 (700 2550);
FORCEPROP 1 LAST MATERIAL CHIP
J 0
(1125 2425);
DISPLAY 0.510638 (1125 2425);
FORCEPROP 1 LAST TOLERANCE 1%
J 0
(1050 2425);
DISPLAY 0.510638 (1050 2425);
FORCEPROP 1 LAST WATTAGE 1/16W
J 2
(1000 2550);
DISPLAY 0.510638 (1000 2550);
FORCEPROP 1 LAST $LOCATION R3592
J 0
(575 2425);
DISPLAY 0.808511 (575 2425);
FORCEPROP 1 LASTPIN (725 2425) $PN 1
J 0
(737 2437);
DISPLAY 0.787234 (737 2437);
FORCEPROP 1 LASTPIN (925 2425) $PN 2
J 0
(887 2437);
DISPLAY 0.787234 (887 2437);
FORCEPROP 2 LAST CDS_LIB pure_quanta
J 0
(825 2425);
DISPLAY INVISIBLE (825 2425);
FORCEPROP 1 LAST PATH I20
J 0
(775 2575);
DISPLAY 0.978723 (775 2575);
PAINT WHITE (775 2575);
DISPLAY INVISIBLE (775 2575);
FORCEPROP 0 LAST CDS_LOCATION R3592
J 0
(1000 2575);
DISPLAY 1.021277 (1000 2575);
DISPLAY INVISIBLE (1000 2575);
FORCEPROP 0 LAST $SEC 1
J 0
(1000 2575);
DISPLAY 0.680851 (1000 2575);
PAINT MONO (1000 2575);
DISPLAY INVISIBLE (1000 2575);
FORCEPROP 0 LAST CDS_SEC 1
J 0
(1000 2575);
DISPLAY 1.021277 (1000 2575);
DISPLAY INVISIBLE (1000 2575);
FORCEADD Q_RES..1
(850 2700);
FORCEPROP 1 LAST PART_NUMBER CS03322FB03
J 0
(725 2775);
DISPLAY 0.510638 (725 2775);
DISPLAY INVISIBLE (725 2775);
FORCEPROP 1 LAST WATTAGE 1/16W
J 2
(1025 2825);
DISPLAY 0.510638 (1025 2825);
FORCEPROP 1 LAST TOLERANCE 1%
J 0
(1075 2700);
DISPLAY 0.510638 (1075 2700);
FORCEPROP 1 LAST MATERIAL CHIP
J 0
(1150 2700);
DISPLAY 0.510638 (1150 2700);
FORCEPROP 1 LAST PACK_TYPE 0402LF
J 0
(725 2825);
DISPLAY 0.510638 (725 2825);
FORCEPROP 1 LAST VALUE 33.2
J 2
(1050 2700);
DISPLAY 0.510638 (1050 2700);
FORCEPROP 1 LAST $LOCATION R3594
J 0
(600 2700);
DISPLAY 0.787234 (600 2700);
FORCEPROP 1 LASTPIN (750 2700) $PN 1
J 0
(762 2712);
DISPLAY 0.787234 (762 2712);
FORCEPROP 1 LASTPIN (950 2700) $PN 2
J 0
(912 2712);
DISPLAY 0.787234 (912 2712);
FORCEPROP 2 LAST CDS_LIB pure_quanta
J 0
(850 2700);
PAINT MONO (850 2700);
DISPLAY INVISIBLE (850 2700);
FORCEPROP 1 LAST PATH I21
J 0
(800 2850);
DISPLAY 0.978723 (800 2850);
PAINT WHITE (800 2850);
DISPLAY INVISIBLE (800 2850);
FORCEPROP 2 LAST CDS_LOCATION R3594
J 0
(800 2900);
DISPLAY 1.021277 (800 2900);
DISPLAY INVISIBLE (800 2900);
FORCEPROP 2 LAST $SEC 1
J 0
(800 2900);
DISPLAY 0.680851 (800 2900);
PAINT MONO (800 2900);
DISPLAY INVISIBLE (800 2900);
FORCEPROP 2 LAST CDS_SEC 1
J 0
(800 2900);
DISPLAY 1.021277 (800 2900);
DISPLAY INVISIBLE (800 2900);
FORCEADD OFFPAGE..2
(2500 2425);
FORCEPROP 2 LAST $XR0 172 
J 0
(2689 2425);
DISPLAY 0.638298 (2689 2425);
PAINT MONO (2689 2425);
FORCEPROP 1 LAST COMMENT_BODY TRUE
J 0
(2455 2330);
DISPLAY 1.170213 (2455 2330);
PAINT GREEN (2455 2330);
DISPLAY INVISIBLE (2455 2330);
FORCEPROP 1 LAST OFFPAGE TRUE
J 0
(2825 2300);
DISPLAY 1.170213 (2825 2300);
PAINT GREEN (2825 2300);
DISPLAY INVISIBLE (2825 2300);
FORCEPROP 2 LAST CDS_LIB standard
J 0
(2500 2425);
PAINT MONO (2500 2425);
DISPLAY INVISIBLE (2500 2425);
FORCEPROP 2 LAST PATH I22
J 0
(2825 2475);
DISPLAY 1.021277 (2825 2475);
DISPLAY INVISIBLE (2825 2475);
FORCEADD OFFPAGE..3
(2500 2375);
FORCEPROP 2 LAST $XR0 172 
J 0
(2714 2375);
DISPLAY 0.638298 (2714 2375);
PAINT MONO (2714 2375);
FORCEPROP 2 LAST CDS_LIB standard
J 0
(2500 2375);
PAINT MONO (2500 2375);
DISPLAY INVISIBLE (2500 2375);
FORCEPROP 1 LAST COMMENT_BODY TRUE
J 0
(2450 2275);
DISPLAY 0.872340 (2450 2275);
PAINT GREEN (2450 2275);
DISPLAY INVISIBLE (2450 2275);
FORCEPROP 1 LAST OFFPAGE TRUE
J 0
(2825 2250);
DISPLAY 0.872340 (2825 2250);
DISPLAY INVISIBLE (2825 2250);
FORCEPROP 2 LAST PATH I23
J 0
(2850 2425);
DISPLAY 1.021277 (2850 2425);
DISPLAY INVISIBLE (2850 2425);
FORCEADD OFFPAGE..2
(2525 2700);
FORCEPROP 2 LAST $XR0 172 
J 0
(2714 2700);
DISPLAY 0.638298 (2714 2700);
PAINT MONO (2714 2700);
FORCEPROP 2 LAST CDS_LIB standard
J 0
(2525 2700);
PAINT MONO (2525 2700);
DISPLAY INVISIBLE (2525 2700);
FORCEPROP 1 LAST OFFPAGE TRUE
J 0
(2850 2575);
DISPLAY 1.170213 (2850 2575);
PAINT GREEN (2850 2575);
DISPLAY INVISIBLE (2850 2575);
FORCEPROP 1 LAST COMMENT_BODY TRUE
J 0
(2480 2605);
DISPLAY 1.170213 (2480 2605);
PAINT GREEN (2480 2605);
DISPLAY INVISIBLE (2480 2605);
FORCEPROP 2 LAST PATH I24
J 0
(2975 2750);
DISPLAY 1.021277 (2975 2750);
DISPLAY INVISIBLE (2975 2750);
FORCEADD OFFPAGE..3
(2525 2650);
FORCEPROP 2 LAST $XR0 172 
J 0
(2739 2650);
DISPLAY 0.638298 (2739 2650);
PAINT MONO (2739 2650);
FORCEPROP 1 LAST OFFPAGE TRUE
J 0
(2850 2525);
DISPLAY 0.872340 (2850 2525);
DISPLAY INVISIBLE (2850 2525);
FORCEPROP 1 LAST COMMENT_BODY TRUE
J 0
(2475 2550);
DISPLAY 0.872340 (2475 2550);
PAINT GREEN (2475 2550);
DISPLAY INVISIBLE (2475 2550);
FORCEPROP 2 LAST CDS_LIB standard
J 0
(2525 2650);
PAINT MONO (2525 2650);
DISPLAY INVISIBLE (2525 2650);
FORCEPROP 2 LAST PATH I25
J 0
(3000 2700);
DISPLAY 1.021277 (3000 2700);
DISPLAY INVISIBLE (3000 2700);
FORCEADD Q_RES..1
(850 2650);
FORCEPROP 1 LAST PART_NUMBER CS03322FB03
J 0
(725 2700);
DISPLAY 0.638298 (725 2700);
DISPLAY INVISIBLE (725 2700);
FORCEPROP 1 LAST MATERIAL CHIP
J 0
(1150 2650);
DISPLAY 0.510638 (1150 2650);
FORCEPROP 1 LAST TOLERANCE 1%
J 0
(1075 2650);
DISPLAY 0.510638 (1075 2650);
FORCEPROP 1 LAST VALUE 33.2
J 2
(1050 2650);
DISPLAY 0.510638 (1050 2650);
FORCEPROP 1 LAST $LOCATION R3595
J 0
(600 2650);
DISPLAY 0.787234 (600 2650);
FORCEPROP 1 LASTPIN (750 2650) $PN 1
J 0
(762 2662);
DISPLAY 0.787234 (762 2662);
FORCEPROP 1 LASTPIN (950 2650) $PN 2
J 0
(912 2662);
DISPLAY 0.787234 (912 2662);
FORCEPROP 1 LAST WATTAGE 1/16W
J 2
(1050 2750);
DISPLAY 0.638298 (1050 2750);
DISPLAY INVISIBLE (1050 2750);
FORCEPROP 1 LAST PACK_TYPE 0402LF
J 0
(1200 2650);
DISPLAY 0.638298 (1200 2650);
DISPLAY INVISIBLE (1200 2650);
FORCEPROP 2 LAST CDS_LIB pure_quanta
J 0
(850 2650);
PAINT MONO (850 2650);
DISPLAY INVISIBLE (850 2650);
FORCEPROP 1 LAST PATH I26
J 0
(800 2800);
DISPLAY 0.978723 (800 2800);
PAINT WHITE (800 2800);
DISPLAY INVISIBLE (800 2800);
FORCEPROP 2 LAST CDS_LOCATION R3595
J 0
(800 2850);
DISPLAY 1.021277 (800 2850);
DISPLAY INVISIBLE (800 2850);
FORCEPROP 2 LAST $SEC 1
J 0
(800 2850);
DISPLAY 0.680851 (800 2850);
PAINT MONO (800 2850);
DISPLAY INVISIBLE (800 2850);
FORCEPROP 2 LAST CDS_SEC 1
J 0
(800 2850);
DISPLAY 1.021277 (800 2850);
DISPLAY INVISIBLE (800 2850);
FORCEADD Q_RES..1
(825 3575);
FORCEPROP 1 LAST PART_NUMBER CS03322FB03
J 0
(700 3625);
DISPLAY 0.638298 (700 3625);
DISPLAY INVISIBLE (700 3625);
FORCEPROP 1 LAST TOLERANCE 1%
J 0
(1050 3575);
DISPLAY 0.510638 (1050 3575);
FORCEPROP 1 LAST VALUE 33.2
J 2
(1025 3575);
DISPLAY 0.510638 (1025 3575);
FORCEPROP 1 LAST MATERIAL CHIP
J 0
(1125 3575);
DISPLAY 0.510638 (1125 3575);
FORCEPROP 1 LAST $LOCATION R3587
J 0
(575 3575);
DISPLAY 0.808511 (575 3575);
FORCEPROP 1 LASTPIN (725 3575) $PN 1
J 0
(737 3587);
DISPLAY 0.787234 (737 3587);
FORCEPROP 1 LASTPIN (925 3575) $PN 2
J 0
(887 3587);
DISPLAY 0.787234 (887 3587);
FORCEPROP 2 LAST CDS_LIB pure_quanta
J 0
(825 3575);
DISPLAY INVISIBLE (825 3575);
FORCEPROP 1 LAST PATH I3
J 0
(775 3725);
DISPLAY 0.978723 (775 3725);
PAINT WHITE (775 3725);
DISPLAY INVISIBLE (775 3725);
FORCEPROP 1 LAST WATTAGE 1/16W
J 2
(1025 3675);
DISPLAY 0.638298 (1025 3675);
DISPLAY INVISIBLE (1025 3675);
FORCEPROP 1 LAST PACK_TYPE 0402LF
J 0
(1175 3575);
DISPLAY 0.638298 (1175 3575);
DISPLAY INVISIBLE (1175 3575);
FORCEPROP 0 LAST CDS_LOCATION R3587
J 0
(575 3625);
DISPLAY 1.021277 (575 3625);
DISPLAY INVISIBLE (575 3625);
FORCEPROP 0 LAST $SEC 1
J 0
(575 3625);
DISPLAY 0.680851 (575 3625);
PAINT MONO (575 3625);
DISPLAY INVISIBLE (575 3625);
FORCEPROP 0 LAST CDS_SEC 1
J 0
(575 3625);
DISPLAY 1.021277 (575 3625);
DISPLAY INVISIBLE (575 3625);
FORCEADD Q_RES..1
(825 3625);
FORCEPROP 1 LAST PART_NUMBER CS03322FB03
J 0
(700 3700);
DISPLAY 0.510638 (700 3700);
DISPLAY INVISIBLE (700 3700);
FORCEPROP 1 LAST WATTAGE 1/16W
J 2
(1000 3750);
DISPLAY 0.510638 (1000 3750);
FORCEPROP 1 LAST PACK_TYPE 0402LF
J 0
(700 3750);
DISPLAY 0.510638 (700 3750);
FORCEPROP 1 LAST MATERIAL CHIP
J 0
(1125 3625);
DISPLAY 0.510638 (1125 3625);
FORCEPROP 1 LAST VALUE 33.2
J 2
(1025 3625);
DISPLAY 0.510638 (1025 3625);
FORCEPROP 1 LAST TOLERANCE 1%
J 0
(1050 3625);
DISPLAY 0.510638 (1050 3625);
FORCEPROP 1 LAST $LOCATION R3586
J 0
(575 3625);
DISPLAY 0.808511 (575 3625);
FORCEPROP 1 LASTPIN (725 3625) $PN 1
J 0
(737 3637);
DISPLAY 0.787234 (737 3637);
FORCEPROP 1 LASTPIN (925 3625) $PN 2
J 0
(887 3637);
DISPLAY 0.787234 (887 3637);
FORCEPROP 2 LAST CDS_LIB pure_quanta
J 0
(825 3625);
DISPLAY INVISIBLE (825 3625);
FORCEPROP 1 LAST PATH I4
J 0
(775 3775);
DISPLAY 0.978723 (775 3775);
PAINT WHITE (775 3775);
DISPLAY INVISIBLE (775 3775);
FORCEPROP 0 LAST CDS_LOCATION R3586
J 0
(1000 3775);
DISPLAY 1.021277 (1000 3775);
DISPLAY INVISIBLE (1000 3775);
FORCEPROP 0 LAST $SEC 1
J 0
(1000 3775);
DISPLAY 0.680851 (1000 3775);
PAINT MONO (1000 3775);
DISPLAY INVISIBLE (1000 3775);
FORCEPROP 0 LAST CDS_SEC 1
J 0
(1000 3775);
DISPLAY 1.021277 (1000 3775);
DISPLAY INVISIBLE (1000 3775);
FORCEADD OFFPAGE..3
(2500 3575);
FORCEPROP 2 LAST $XR0 171 
J 0
(2714 3575);
DISPLAY 0.638298 (2714 3575);
PAINT MONO (2714 3575);
FORCEPROP 2 LAST PATH I7
J 0
(2850 3625);
DISPLAY 1.021277 (2850 3625);
DISPLAY INVISIBLE (2850 3625);
FORCEPROP 2 LAST CDS_LIB standard
J 0
(2500 3575);
PAINT MONO (2500 3575);
DISPLAY INVISIBLE (2500 3575);
FORCEPROP 1 LAST COMMENT_BODY TRUE
J 0
(2450 3475);
DISPLAY 0.872340 (2450 3475);
PAINT GREEN (2450 3475);
DISPLAY INVISIBLE (2450 3475);
FORCEPROP 1 LAST OFFPAGE TRUE
J 0
(2825 3450);
DISPLAY 0.872340 (2825 3450);
DISPLAY INVISIBLE (2825 3450);
FORCEADD OFFPAGE..2
(2500 3625);
FORCEPROP 2 LAST $XR0 171 
J 0
(2689 3625);
DISPLAY 0.638298 (2689 3625);
PAINT MONO (2689 3625);
FORCEPROP 2 LAST PATH I8
J 0
(2825 3675);
DISPLAY 1.021277 (2825 3675);
DISPLAY INVISIBLE (2825 3675);
FORCEPROP 1 LAST COMMENT_BODY TRUE
J 0
(2455 3530);
DISPLAY 1.170213 (2455 3530);
PAINT GREEN (2455 3530);
DISPLAY INVISIBLE (2455 3530);
FORCEPROP 1 LAST OFFPAGE TRUE
J 0
(2825 3500);
DISPLAY 1.170213 (2825 3500);
PAINT GREEN (2825 3500);
DISPLAY INVISIBLE (2825 3500);
FORCEPROP 2 LAST CDS_LIB standard
J 0
(2500 3625);
PAINT MONO (2500 3625);
DISPLAY INVISIBLE (2500 3625);
FORCEADD QUANTA_TITLE_BLOCK_C..1
(5375 -1775);
FORCEPROP 0 LAST CDS_CON_LAST_MODIFIED Fri Aug 25 14:03:55 2023
J 0
(3490 -1760);
PAINT MONO (3490 -1760);
DISPLAY INVISIBLE (3490 -1760);
FORCEPROP 2 LAST CUSTOM_TXT_CDS <XR_PAGE_TITLE>
J 0
(-2515 3475);
DISPLAY 0.638298 (-2515 3475);
PAINT PINK (-2515 3475);
DISPLAY INVISIBLE (-2515 3475);
FORCEPROP 2 LAST CUSTOM_TXT_CDS <CON_LAST_MODIFIED>
J 0
(3490 -1760);
DISPLAY 0.978723 (3490 -1760);
FORCEPROP 2 LAST CUSTOM_TXT_CDS <Q_NUMBER>
J 0
(3972 -1672);
DISPLAY 1.212766 (3972 -1672);
FORCEPROP 2 LAST CUSTOM_TXT_CDS <Q_REV>
J 0
(5191 -1672);
DISPLAY 1.212766 (5191 -1672);
FORCEPROP 2 LAST CUSTOM_TXT_CDS <Q_PROJ>
J 0
(2993 -1673);
DISPLAY 1.212766 (2993 -1673);
FORCEPROP 2 LAST CUSTOM_TXT_CDS <NAME_1>
J 0
(2200 -1600);
FORCEPROP 2 LAST CUSTOM_TXT_CDS <NAME_2>
J 0
(2200 -1725);
FORCEPROP 2 LAST CUSTOM_TXT_CDS <CON_PAGE_NUM> OF <CON_TOTAL_PAGES>
J 0
(4929 -1757);
DISPLAY 0.978723 (4929 -1757);
FORCEPROP 1 LAST Q_TITLE SMBUS - PCIE1  SMBUS
J 0
(-3891 -1749);
DISPLAY 2.446809 (-3891 -1749);
PAINT GREEN (-3891 -1749);
FORCEPROP 1 LAST Q_DEPT 
J 1
(1612 -1726);
DISPLAY 1.957447 (1612 -1726);
PAINT GREEN (1612 -1726);
FORCEPROP 2 LAST CDS_XR_PAGE_TITLE CR-232 : @S9S_MB_2U_LIB.S9S_MB_2U(SCH_1):PAGE232
J 0
(-2515 3475);
DISPLAY 0.638298 (-2515 3475);
PAINT PINK (-2515 3475);
DISPLAY INVISIBLE (-2515 3475);
FORCEPROP 2 LAST PAGE_BORDER TRUE
J 0
(-2515 3475);
DISPLAY 0.638298 (-2515 3475);
PAINT PINK (-2515 3475);
DISPLAY INVISIBLE (-2515 3475);
FORCEPROP 1 LAST COMMENT_BODY TRUE
J 0
(5387 -1788);
DISPLAY 0.978723 (5387 -1788);
PAINT GREEN (5387 -1788);
DISPLAY INVISIBLE (5387 -1788);
FORCEPROP 1 LAST CDS_LMAN_SYM_OUTLINE -9475,6775,100,-125
J 0
(5375 -1775);
DISPLAY 0.468085 (5375 -1775);
PAINT GREEN (5375 -1775);
DISPLAY INVISIBLE (5375 -1775);
FORCEPROP 2 LAST CDS_LIB pure_quanta
J 0
(5375 -1775);
PAINT MONO (5375 -1775);
DISPLAY INVISIBLE (5375 -1775);
WIRE 16 -1 (425 2425)(725 2425);
WIRE 16 -1 (425 2700)(425 2425);
WIRE 16 -1 (750 2700)(425 2700);
WIRE 16 -1 (425 3000)(425 2700);
WIRE 16 -1 (425 3000)(725 3000);
WIRE 16 -1 (425 3275)(425 3000);
WIRE 16 -1 (425 3275)(725 3275);
WIRE 16 -1 (425 3625)(425 3275);
WIRE 16 -1 (425 3625)(725 3625);
WIRE 16 -1 (-850 3625)(425 3625);
FORCEPROP 2 LAST SIG_NAME SMB_INA230_3V3AUX_SCL
J 0
(-710 3635);
DISPLAY 0.680851 (-710 3635);
PAINT WHITE (-710 3635);
WIRE 16 -1 (925 3225)(2450 3225);
FORCEPROP 2 LAST SIG_NAME SMB_INA230_2_3V3AUX_SDA_R
J 0
(1440 3235);
DISPLAY 0.680851 (1440 3235);
PAINT WHITE (1440 3235);
WIRE 16 -1 (925 3275)(2450 3275);
FORCEPROP 2 LAST SIG_NAME SMB_INA230_2_3V3AUX_SCL_R
J 0
(1440 3285);
DISPLAY 0.680851 (1440 3285);
PAINT WHITE (1440 3285);
WIRE 16 -1 (725 2375)(375 2375);
WIRE 16 -1 (375 2375)(375 2650);
WIRE 16 -1 (750 2650)(375 2650);
WIRE 16 -1 (375 2950)(375 2650);
WIRE 16 -1 (375 2950)(725 2950);
WIRE 16 -1 (375 3225)(375 2950);
WIRE 16 -1 (375 3225)(725 3225);
WIRE 16 -1 (375 3575)(375 3225);
WIRE 16 -1 (375 3575)(725 3575);
WIRE 16 -1 (-850 3575)(375 3575);
FORCEPROP 2 LAST SIG_NAME SMB_INA230_3V3AUX_SDA
J 0
(-710 3585);
DISPLAY 0.680851 (-710 3585);
PAINT WHITE (-710 3585);
WIRE 16 -1 (925 3575)(2450 3575);
FORCEPROP 2 LAST SIG_NAME SMB_INA230_1_3V3AUX_SDA_R
J 0
(1440 3585);
DISPLAY 0.680851 (1440 3585);
PAINT WHITE (1440 3585);
WIRE 16 -1 (925 3625)(2450 3625);
FORCEPROP 2 LAST SIG_NAME SMB_INA230_1_3V3AUX_SCL_R
J 0
(1440 3635);
DISPLAY 0.680851 (1440 3635);
PAINT WHITE (1440 3635);
WIRE 16 -1 (925 2375)(2450 2375);
FORCEPROP 2 LAST SIG_NAME SMB_INA230_5_3V3AUX_SDA_R
J 0
(1440 2385);
DISPLAY 0.680851 (1440 2385);
PAINT WHITE (1440 2385);
WIRE 16 -1 (925 3000)(2450 3000);
FORCEPROP 2 LAST SIG_NAME SMB_INA230_3_3V3AUX_SCL_R
J 0
(1440 3010);
DISPLAY 0.680851 (1440 3010);
PAINT WHITE (1440 3010);
WIRE 16 -1 (925 2950)(2450 2950);
FORCEPROP 2 LAST SIG_NAME SMB_INA230_3_3V3AUX_SDA_R
J 0
(1440 2960);
DISPLAY 0.680851 (1440 2960);
PAINT WHITE (1440 2960);
WIRE 16 -1 (950 2700)(2475 2700);
FORCEPROP 2 LAST SIG_NAME SMB_INA230_4_3V3AUX_SCL_R
J 0
(1465 2710);
DISPLAY 0.680851 (1465 2710);
PAINT WHITE (1465 2710);
WIRE 16 -1 (950 2650)(2475 2650);
FORCEPROP 2 LAST SIG_NAME SMB_INA230_4_3V3AUX_SDA_R
J 0
(1465 2660);
DISPLAY 0.680851 (1465 2660);
PAINT WHITE (1465 2660);
WIRE 16 -1 (925 2425)(2450 2425);
FORCEPROP 2 LAST SIG_NAME SMB_INA230_5_3V3AUX_SCL_R
J 0
(1440 2435);
DISPLAY 0.680851 (1440 2435);
PAINT WHITE (1440 2435);
DOT 1 (425 3625);
DOT 1 (375 3575);
DOT 1 (425 3275);
DOT 1 (375 2950);
DOT 1 (425 2700);
DOT 1 (375 2650);
DOT 1 (375 3225);
DOT 1 (425 3000);
FORCENOTE
20210622 MODIFY FOR GT
(1000 4250) 0;
DISPLAY LEFT (1000 4250);
DISPLAY 2.510638 (1000 4250);
PAINT PINK (1000 4250);
QUIT
